(kicad_pcb
	(version 20260206)
	(generator "pcbnew")
	(generator_version "10.0")
	(general
		(thickness 1.6)
		(legacy_teardrops no)
	)
	(paper "A4")
	(title_block
		(title "03242023_DA0F0TMBIJ0_F0T_Motherboard_J_brd_V01_OCP.brd")
		(comment 1 "Grand Teton / footprints 3066-3070 of 6105")
	)
	(layers
		(0 "F.Cu" signal "TOP")
		(4 "In1.Cu" signal "GND")
		(6 "In2.Cu" signal "IN1")
		(8 "In3.Cu" signal "GND1")
		(10 "In4.Cu" signal "IN2")
		(12 "In5.Cu" signal "GND2")
		(14 "In6.Cu" signal "IN3")
		(16 "In7.Cu" signal "GND3")
		(18 "In8.Cu" signal "VCC")
		(20 "In9.Cu" signal "VCC1")
		(22 "In10.Cu" signal "GND4")
		(24 "In11.Cu" signal "IN4")
		(26 "In12.Cu" signal "GND5")
		(28 "In13.Cu" signal "IN5")
		(30 "In14.Cu" signal "GND6")
		(32 "In15.Cu" signal "IN6")
		(34 "In16.Cu" signal "GND7")
		(2 "B.Cu" signal "BOTTOM")
		(9 "F.Adhes" user "F.Adhesive")
		(11 "B.Adhes" user "B.Adhesive")
		(13 "F.Paste" user "Package Geometry/Pastemask Top")
		(15 "B.Paste" user "Package Geometry/Pastemask Bottom")
		(5 "F.SilkS" user "Ref Des/Silkscreen Top")
		(7 "B.SilkS" user "Ref Des/Silkscreen Bottom")
		(1 "F.Mask" user "Board Geometry/Soldermask Top")
		(3 "B.Mask" user "Board Geometry/Soldermask Bottom")
		(17 "Dwgs.User" user "User.Drawings")
		(19 "Cmts.User" user "User.Comments")
		(21 "Eco1.User" user "User.Eco1")
		(23 "Eco2.User" user "User.Eco2")
		(25 "Edge.Cuts" user "Board Geometry/Outline")
		(27 "Margin" user)
		(31 "F.CrtYd" user "Package Geometry/Place Bound Top")
		(29 "B.CrtYd" user "Package Geometry/Place Bound Bottom")
		(35 "F.Fab" user "Ref Des/Assembly Top")
		(33 "B.Fab" user "Ref Des/Assembly Bottom")
	)
	(footprint ""
		(layer "F.Cu")
		(at 219.276676 -67.954144 -90)
		(property "Reference" "PR3964"
			(at 0 0 270)
			(layer "F.SilkS")
			(hide yes)
			(effects
				(font
					(size 1.27 1.27)
				)
			)
		)
		(property "Value" ""
			(at 0 0 270)
			(layer "F.Fab")
			(effects
				(font
					(size 1.27 1.27)
				)
			)
		)
		(duplicate_pad_numbers_are_jumpers no)
		(fp_line
			(start -0.7874 0.4064)
			(end -0.7874 -0.4064)
			(stroke
				(width 0.1524)
				(type default)
			)
			(layer "F.SilkS")
		)
		(fp_line
			(start 0.7874 0.4064)
			(end -0.7874 0.4064)
			(stroke
				(width 0.1524)
				(type default)
			)
			(layer "F.SilkS")
		)
		(fp_line
			(start -0.7874 -0.4064)
			(end 0.7874 -0.4064)
			(stroke
				(width 0.1524)
				(type default)
			)
			(layer "F.SilkS")
		)
		(fp_line
			(start 0.7874 -0.4064)
			(end 0.7874 0.4064)
			(stroke
				(width 0.1524)
				(type default)
			)
			(layer "F.SilkS")
		)
		(fp_line
			(start -0.67945 0.3048)
			(end -0.67945 -0.305054)
			(stroke
				(width 0.1)
				(type default)
			)
			(layer "F.Fab")
		)
		(fp_line
			(start -0.12065 0.3048)
			(end -0.67945 0.3048)
			(stroke
				(width 0.1)
				(type default)
			)
			(layer "F.Fab")
		)
		(fp_line
			(start 0.120396 0.3048)
			(end 0.120396 0.2794)
			(stroke
				(width 0.1)
				(type default)
			)
			(layer "F.Fab")
		)
		(fp_line
			(start 0.67945 0.3048)
			(end 0.120396 0.3048)
			(stroke
				(width 0.1)
				(type default)
			)
			(layer "F.Fab")
		)
		(fp_line
			(start -0.12065 0.2794)
			(end -0.12065 0.3048)
			(stroke
				(width 0.1)
				(type default)
			)
			(layer "F.Fab")
		)
		(fp_line
			(start 0.120396 0.2794)
			(end -0.12065 0.2794)
			(stroke
				(width 0.1)
				(type default)
			)
			(layer "F.Fab")
		)
		(fp_line
			(start -0.12065 -0.2794)
			(end 0.12065 -0.2794)
			(stroke
				(width 0.1)
				(type default)
			)
			(layer "F.Fab")
		)
		(fp_line
			(start 0.12065 -0.2794)
			(end 0.12065 -0.3048)
			(stroke
				(width 0.1)
				(type default)
			)
			(layer "F.Fab")
		)
		(fp_line
			(start 0.12065 -0.3048)
			(end 0.67945 -0.3048)
			(stroke
				(width 0.1)
				(type default)
			)
			(layer "F.Fab")
		)
		(fp_line
			(start 0.67945 -0.3048)
			(end 0.67945 0.3048)
			(stroke
				(width 0.1)
				(type default)
			)
			(layer "F.Fab")
		)
		(fp_line
			(start -0.67945 -0.305054)
			(end -0.12065 -0.305054)
			(stroke
				(width 0.1)
				(type default)
			)
			(layer "F.Fab")
		)
		(fp_line
			(start -0.12065 -0.305054)
			(end -0.12065 -0.2794)
			(stroke
				(width 0.1)
				(type default)
			)
			(layer "F.Fab")
		)
		(pad "1" smd circle
			(at -0.40005 0 270)
			(size 0 0)
			(layers "F.Cu" "F.Mask" "F.Paste")
			(net "P3V3_E1S_UV_0")
		)
		(pad "2" smd circle
			(at 0.40005 0 270)
			(size 0 0)
			(layers "F.Cu" "F.Mask" "F.Paste")
			(net "P3V3_E1S_OV_0")
		)
	)
	(footprint ""
		(layer "F.Cu")
		(at 67.672458 -27.889962 -90)
		(property "Reference" "PU206"
			(at -0.065532 -4.389628 0)
			(unlocked yes)
			(layer "F.SilkS")
			(effects
				(font
					(size 0.7874 0.5842)
					(thickness 0.1524)
				)
				(justify left)
			)
		)
		(property "Value" ""
			(at 0 0 270)
			(layer "F.Fab")
			(effects
				(font
					(size 1.27 1.27)
				)
			)
		)
		(duplicate_pad_numbers_are_jumpers no)
		(fp_line
			(start -1.549908 2.549906)
			(end -0.753872 2.549906)
			(stroke
				(width 0.1524)
				(type default)
			)
			(layer "F.SilkS")
		)
		(fp_line
			(start -0.245872 2.549906)
			(end 0.245872 2.549906)
			(stroke
				(width 0.1524)
				(type default)
			)
			(layer "F.SilkS")
		)
		(fp_line
			(start 0.753872 2.549906)
			(end 1.549908 2.549906)
			(stroke
				(width 0.1524)
				(type default)
			)
			(layer "F.SilkS")
		)
		(fp_line
			(start 1.549908 2.549906)
			(end 1.549908 2.253996)
			(stroke
				(width 0.1524)
				(type default)
			)
			(layer "F.SilkS")
		)
		(fp_line
			(start -1.549908 2.253996)
			(end -1.549908 2.549906)
			(stroke
				(width 0.1524)
				(type default)
			)
			(layer "F.SilkS")
		)
		(fp_line
			(start 1.549908 -2.253996)
			(end 1.549908 -2.549906)
			(stroke
				(width 0.1524)
				(type default)
			)
			(layer "F.SilkS")
		)
		(fp_line
			(start -1.549908 -2.549906)
			(end -1.549908 -2.251964)
			(stroke
				(width 0.1524)
				(type default)
			)
			(layer "F.SilkS")
		)
		(fp_line
			(start -0.752094 -2.549906)
			(end -1.549908 -2.549906)
			(stroke
				(width 0.1524)
				(type default)
			)
			(layer "F.SilkS")
		)
		(fp_line
			(start 0.2413 -2.549906)
			(end -0.2413 -2.549906)
			(stroke
				(width 0.1524)
				(type default)
			)
			(layer "F.SilkS")
		)
		(fp_line
			(start 1.549908 -2.549906)
			(end 0.752094 -2.549906)
			(stroke
				(width 0.1524)
				(type default)
			)
			(layer "F.SilkS")
		)
		(fp_poly
			(pts
				(xy -2.83845 -2.769616) (xy -2.23647 -3.37185) (xy -1.935226 -2.468626)
			)
			(stroke
				(width 0)
				(type default)
			)
			(fill yes)
			(layer "F.SilkS")
		)
		(fp_line
			(start -1.549908 2.549906)
			(end 1.549908 2.549906)
			(stroke
				(width 0.1)
				(type default)
			)
			(layer "F.Fab")
		)
		(fp_line
			(start 1.549908 2.549906)
			(end 1.549908 -2.549906)
			(stroke
				(width 0.1)
				(type default)
			)
			(layer "F.Fab")
		)
		(fp_line
			(start -1.549908 -2.549906)
			(end -1.549908 2.549906)
			(stroke
				(width 0.1)
				(type default)
			)
			(layer "F.Fab")
		)
		(fp_line
			(start 1.549908 -2.549906)
			(end -1.549908 -2.549906)
			(stroke
				(width 0.1)
				(type default)
			)
			(layer "F.Fab")
		)
		(fp_poly
			(pts
				(xy -1.891538 -1.999996) (xy -2.7432 -1.574292) (xy -2.7432 -2.4257)
			)
			(stroke
				(width 0)
				(type default)
			)
			(fill yes)
			(layer "F.Fab")
		)
		(fp_text user "12"
			(at 4.230624 5.597398 0)
			(unlocked yes)
			(layer "F.SilkS")
			(effects
				(font
					(size 0.635 0.4064)
					(thickness 0.1524)
				)
			)
		)
		(fp_text user "11"
			(at 2.996184 5.389118 0)
			(unlocked yes)
			(layer "F.SilkS")
			(effects
				(font
					(size 0.635 0.4064)
					(thickness 0.1524)
				)
			)
		)
		(fp_text user "10"
			(at -2.393696 3.639058 0)
			(unlocked yes)
			(layer "F.SilkS")
			(effects
				(font
					(size 0.635 0.4064)
					(thickness 0.1524)
				)
			)
		)
		(fp_text user "9"
			(at -2.338832 2.5908 180)
			(unlocked yes)
			(layer "F.SilkS")
			(effects
				(font
					(size 0.635 0.4064)
					(thickness 0.1524)
				)
			)
		)
		(fp_text user "20"
			(at 1.510284 -3.318002 0)
			(unlocked yes)
			(layer "F.SilkS")
			(effects
				(font
					(size 0.635 0.4064)
					(thickness 0.1524)
				)
			)
		)
		(fp_text user "21_22"
			(at -3.696716 -4.349242 0)
			(unlocked yes)
			(layer "F.SilkS")
			(effects
				(font
					(size 0.635 0.4064)
					(thickness 0.1524)
				)
			)
		)
		(fp_text user "11"
			(at 1.1938 3.329432 270)
			(unlocked yes)
			(layer "F.Fab")
			(effects
				(font
					(size 0.635 0.4064)
					(thickness 0.1524)
				)
			)
		)
		(fp_text user "10"
			(at -1.4224 3.253232 270)
			(unlocked yes)
			(layer "F.Fab")
			(effects
				(font
					(size 0.635 0.4064)
					(thickness 0.1524)
				)
			)
		)
		(fp_text user "12"
			(at 2.207768 2.7178 180)
			(unlocked yes)
			(layer "F.Fab")
			(effects
				(font
					(size 0.635 0.4064)
					(thickness 0.1524)
				)
			)
		)
		(fp_text user "9"
			(at -2.338832 2.5908 180)
			(unlocked yes)
			(layer "F.Fab")
			(effects
				(font
					(size 0.635 0.4064)
					(thickness 0.1524)
				)
			)
		)
		(fp_text user "20"
			(at 2.055368 -2.7686 180)
			(unlocked yes)
			(layer "F.Fab")
			(effects
				(font
					(size 0.635 0.4064)
					(thickness 0.1524)
				)
			)
		)
		(fp_text user "21_22"
			(at -0.0762 -3.401568 270)
			(unlocked yes)
			(layer "F.Fab")
			(effects
				(font
					(size 0.635 0.4064)
					(thickness 0.1524)
				)
			)
		)
		(pad "1" smd circle
			(at -1.374902 -1.999996 180)
			(size 0 0)
			(layers "F.Cu" "F.Mask" "F.Paste")
			(net "P12V_OCP_V3_2_EN_2_R3")
		)
		(pad "2" smd rect
			(at -1.400048 -1.500124 180)
			(size 0.254 0.8128)
			(layers "F.Cu" "F.Mask" "F.Paste")
			(net "GND")
		)
		(pad "3" smd rect
			(at -1.400048 -0.999998 180)
			(size 0.254 0.8128)
			(layers "F.Cu" "F.Mask" "F.Paste")
			(net "GND")
		)
		(pad "4" smd rect
			(at -1.400048 -0.499872 180)
			(size 0.254 0.8128)
			(layers "F.Cu" "F.Mask" "F.Paste")
			(net "P12V_OCP_TIMER_2")
		)
		(pad "5" smd rect
			(at -1.400048 0 180)
			(size 0.254 0.8128)
			(layers "F.Cu" "F.Mask" "F.Paste")
			(net "P12V_OCP_ISET_2")
		)
		(pad "6" smd rect
			(at -1.400048 0.499872 180)
			(size 0.254 0.8128)
			(layers "F.Cu" "F.Mask" "F.Paste")
			(net "P12V_OCP_SS_2")
		)
		(pad "7" smd rect
			(at -1.400048 0.999998 180)
			(size 0.254 0.8128)
			(layers "F.Cu" "F.Mask" "F.Paste")
			(net "GND")
		)
		(pad "8" smd rect
			(at -1.400048 1.500124 180)
			(size 0.254 0.8128)
			(layers "F.Cu" "F.Mask" "F.Paste")
			(net "P12V_OCP_IMON_2")
		)
		(pad "9" smd rect
			(at -1.400048 1.999996 180)
			(size 0.254 0.8128)
			(layers "F.Cu" "F.Mask" "F.Paste")
			(net "P12V_OCP_FLTB_2")
		)
		(pad "10" smd rect
			(at -0.499872 2.400046 270)
			(size 0.254 0.8128)
			(layers "F.Cu" "F.Mask" "F.Paste")
			(net "HP_LVC3_OCP_V3_2_P12V_PWRGD")
		)
		(pad "11" smd rect
			(at 0.499872 2.400046 270)
			(size 0.254 0.8128)
			(layers "F.Cu" "F.Mask" "F.Paste")
			(net "P12V_OCP_OV_FB_2")
		)
		(pad "12" smd rect
			(at 1.400048 1.999996 180)
			(size 0.254 0.8128)
			(layers "F.Cu" "F.Mask" "F.Paste")
			(net "P12V_OCP_AVIN_PD_2")
		)
		(pad "13" smd rect
			(at 1.400048 1.500124 180)
			(size 0.254 0.8128)
			(layers "F.Cu" "F.Mask" "F.Paste")
			(net "P12V_OCP_V3_2")
		)
		(pad "14" smd rect
			(at 1.400048 0.999998 180)
			(size 0.254 0.8128)
			(layers "F.Cu" "F.Mask" "F.Paste")
			(net "P12V_OCP_V3_2")
		)
		(pad "15" smd rect
			(at 1.400048 0.499872 180)
			(size 0.254 0.8128)
			(layers "F.Cu" "F.Mask" "F.Paste")
			(net "P12V_OCP_V3_2")
		)
		(pad "16" smd rect
			(at 1.400048 0 180)
			(size 0.254 0.8128)
			(layers "F.Cu" "F.Mask" "F.Paste")
			(net "P12V_OCP_V3_2")
		)
		(pad "17" smd rect
			(at 1.400048 -0.499872 180)
			(size 0.254 0.8128)
			(layers "F.Cu" "F.Mask" "F.Paste")
			(net "P12V_OCP_V3_2")
		)
		(pad "18" smd rect
			(at 1.400048 -0.999998 180)
			(size 0.254 0.8128)
			(layers "F.Cu" "F.Mask" "F.Paste")
			(net "P12V_OCP_V3_2")
		)
		(pad "19" smd rect
			(at 1.400048 -1.500124 180)
			(size 0.254 0.8128)
			(layers "F.Cu" "F.Mask" "F.Paste")
			(net "P12V_OCP_V3_2")
		)
		(pad "20" smd rect
			(at 1.400048 -1.999996 180)
			(size 0.254 0.8128)
			(layers "F.Cu" "F.Mask" "F.Paste")
			(net "P12V_OCP_V3_2")
		)
		(pad "21_22" smd circle
			(at 0.499872 -2.337562 180)
			(size 0 0)
			(layers "F.Cu" "F.Mask" "F.Paste")
			(net "P12V_AUX")
		)
		(pad "23" smd rect
			(at 0 -1.100074 180)
			(size 0.254 1.27)
			(layers "F.Cu" "F.Mask" "F.Paste")
			(net "P12V_AUX")
		)
		(pad "24" smd rect
			(at 0 -0.199898 180)
			(size 0.254 1.27)
			(layers "F.Cu" "F.Mask" "F.Paste")
			(net "P12V_AUX")
		)
		(pad "25" smd rect
			(at 0 0.700024 180)
			(size 0.254 1.27)
			(layers "F.Cu" "F.Mask" "F.Paste")
			(net "P12V_AUX")
		)
		(pad "26" smd rect
			(at 0 1.599946 180)
			(size 0.254 1.27)
			(layers "F.Cu" "F.Mask" "F.Paste")
			(net "P12V_AUX")
		)
	)
	(footprint ""
		(layer "F.Cu")
		(at 353.246944 -240.276888 90)
		(property "Reference" "C1027"
			(at 0 0 90)
			(layer "F.SilkS")
			(hide yes)
			(effects
				(font
					(size 1.27 1.27)
				)
			)
		)
		(property "Value" ""
			(at 0 0 90)
			(layer "F.Fab")
			(effects
				(font
					(size 1.27 1.27)
				)
			)
		)
		(duplicate_pad_numbers_are_jumpers no)
		(fp_line
			(start 0.7874 -0.4064)
			(end 0.7874 0.4064)
			(stroke
				(width 0.1524)
				(type default)
			)
			(layer "F.SilkS")
		)
		(fp_line
			(start -0.7874 -0.4064)
			(end 0.7874 -0.4064)
			(stroke
				(width 0.1524)
				(type default)
			)
			(layer "F.SilkS")
		)
		(fp_line
			(start 0.7874 0.4064)
			(end -0.7874 0.4064)
			(stroke
				(width 0.1524)
				(type default)
			)
			(layer "F.SilkS")
		)
		(fp_line
			(start -0.7874 0.4064)
			(end -0.7874 -0.4064)
			(stroke
				(width 0.1524)
				(type default)
			)
			(layer "F.SilkS")
		)
		(fp_line
			(start -0.12065 -0.305054)
			(end -0.12065 -0.2794)
			(stroke
				(width 0.1)
				(type default)
			)
			(layer "F.Fab")
		)
		(fp_line
			(start -0.67945 -0.305054)
			(end -0.12065 -0.305054)
			(stroke
				(width 0.1)
				(type default)
			)
			(layer "F.Fab")
		)
		(fp_line
			(start 0.67945 -0.3048)
			(end 0.67945 0.3048)
			(stroke
				(width 0.1)
				(type default)
			)
			(layer "F.Fab")
		)
		(fp_line
			(start 0.12065 -0.3048)
			(end 0.67945 -0.3048)
			(stroke
				(width 0.1)
				(type default)
			)
			(layer "F.Fab")
		)
		(fp_line
			(start 0.12065 -0.2794)
			(end 0.12065 -0.3048)
			(stroke
				(width 0.1)
				(type default)
			)
			(layer "F.Fab")
		)
		(fp_line
			(start -0.12065 -0.2794)
			(end 0.12065 -0.2794)
			(stroke
				(width 0.1)
				(type default)
			)
			(layer "F.Fab")
		)
		(fp_line
			(start 0.120396 0.2794)
			(end -0.12065 0.2794)
			(stroke
				(width 0.1)
				(type default)
			)
			(layer "F.Fab")
		)
		(fp_line
			(start -0.12065 0.2794)
			(end -0.12065 0.3048)
			(stroke
				(width 0.1)
				(type default)
			)
			(layer "F.Fab")
		)
		(fp_line
			(start 0.67945 0.3048)
			(end 0.120396 0.3048)
			(stroke
				(width 0.1)
				(type default)
			)
			(layer "F.Fab")
		)
		(fp_line
			(start 0.120396 0.3048)
			(end 0.120396 0.2794)
			(stroke
				(width 0.1)
				(type default)
			)
			(layer "F.Fab")
		)
		(fp_line
			(start -0.12065 0.3048)
			(end -0.67945 0.3048)
			(stroke
				(width 0.1)
				(type default)
			)
			(layer "F.Fab")
		)
		(fp_line
			(start -0.67945 0.3048)
			(end -0.67945 -0.305054)
			(stroke
				(width 0.1)
				(type default)
			)
			(layer "F.Fab")
		)
		(pad "1" smd circle
			(at -0.40005 0 90)
			(size 0 0)
			(layers "F.Cu" "F.Mask" "F.Paste")
			(net "PVCCIN_CPU0")
		)
		(pad "2" smd circle
			(at 0.40005 0 90)
			(size 0 0)
			(layers "F.Cu" "F.Mask" "F.Paste")
			(net "GND")
		)
	)
	(footprint ""
		(layer "F.Cu")
		(at 140.70838 -39.085012 180)
		(property "Reference" "R3308"
			(at 0 0 180)
			(layer "F.SilkS")
			(hide yes)
			(effects
				(font
					(size 1.27 1.27)
				)
			)
		)
		(property "Value" ""
			(at 0 0 180)
			(layer "F.Fab")
			(effects
				(font
					(size 1.27 1.27)
				)
			)
		)
		(duplicate_pad_numbers_are_jumpers no)
		(fp_line
			(start 0.7874 0.4064)
			(end -0.7874 0.4064)
			(stroke
				(width 0.1524)
				(type default)
			)
			(layer "F.SilkS")
		)
		(fp_line
			(start 0.7874 -0.4064)
			(end 0.7874 0.4064)
			(stroke
				(width 0.1524)
				(type default)
			)
			(layer "F.SilkS")
		)
		(fp_line
			(start -0.7874 0.4064)
			(end -0.7874 -0.4064)
			(stroke
				(width 0.1524)
				(type default)
			)
			(layer "F.SilkS")
		)
		(fp_line
			(start -0.7874 -0.4064)
			(end 0.7874 -0.4064)
			(stroke
				(width 0.1524)
				(type default)
			)
			(layer "F.SilkS")
		)
		(fp_line
			(start 0.67945 0.3048)
			(end 0.120396 0.3048)
			(stroke
				(width 0.1)
				(type default)
			)
			(layer "F.Fab")
		)
		(fp_line
			(start 0.67945 -0.3048)
			(end 0.67945 0.3048)
			(stroke
				(width 0.1)
				(type default)
			)
			(layer "F.Fab")
		)
		(fp_line
			(start 0.12065 -0.2794)
			(end 0.12065 -0.3048)
			(stroke
				(width 0.1)
				(type default)
			)
			(layer "F.Fab")
		)
		(fp_line
			(start 0.12065 -0.3048)
			(end 0.67945 -0.3048)
			(stroke
				(width 0.1)
				(type default)
			)
			(layer "F.Fab")
		)
		(fp_line
			(start 0.120396 0.3048)
			(end 0.120396 0.2794)
			(stroke
				(width 0.1)
				(type default)
			)
			(layer "F.Fab")
		)
		(fp_line
			(start 0.120396 0.2794)
			(end -0.12065 0.2794)
			(stroke
				(width 0.1)
				(type default)
			)
			(layer "F.Fab")
		)
		(fp_line
			(start -0.12065 0.3048)
			(end -0.67945 0.3048)
			(stroke
				(width 0.1)
				(type default)
			)
			(layer "F.Fab")
		)
		(fp_line
			(start -0.12065 0.2794)
			(end -0.12065 0.3048)
			(stroke
				(width 0.1)
				(type default)
			)
			(layer "F.Fab")
		)
		(fp_line
			(start -0.12065 -0.2794)
			(end 0.12065 -0.2794)
			(stroke
				(width 0.1)
				(type default)
			)
			(layer "F.Fab")
		)
		(fp_line
			(start -0.12065 -0.305054)
			(end -0.12065 -0.2794)
			(stroke
				(width 0.1)
				(type default)
			)
			(layer "F.Fab")
		)
		(fp_line
			(start -0.67945 0.3048)
			(end -0.67945 -0.305054)
			(stroke
				(width 0.1)
				(type default)
			)
			(layer "F.Fab")
		)
		(fp_line
			(start -0.67945 -0.305054)
			(end -0.12065 -0.305054)
			(stroke
				(width 0.1)
				(type default)
			)
			(layer "F.Fab")
		)
		(pad "1" smd circle
			(at -0.40005 0 180)
			(size 0 0)
			(layers "F.Cu" "F.Mask" "F.Paste")
			(net "OCP_V3_2_PRSNT_ALL_R_N")
		)
		(pad "2" smd circle
			(at 0.40005 0 180)
			(size 0 0)
			(layers "F.Cu" "F.Mask" "F.Paste")
			(net "OCP_V3_2_PRSNT_ALL_R1_N")
		)
	)
	(footprint ""
		(layer "F.Cu")
		(at 342.974168 -408.517344 -90)
		(property "Reference" "C927"
			(at 0 0 270)
			(layer "F.SilkS")
			(hide yes)
			(effects
				(font
					(size 1.27 1.27)
				)
			)
		)
		(property "Value" ""
			(at 0 0 270)
			(layer "F.Fab")
			(effects
				(font
					(size 1.27 1.27)
				)
			)
		)
		(duplicate_pad_numbers_are_jumpers no)
		(fp_line
			(start -0.299974 0.150114)
			(end -0.299974 -0.150114)
			(stroke
				(width 0.1)
				(type default)
			)
			(layer "F.Fab")
		)
		(fp_line
			(start 0.299974 0.150114)
			(end -0.299974 0.150114)
			(stroke
				(width 0.1)
				(type default)
			)
			(layer "F.Fab")
		)
		(fp_line
			(start -0.299974 -0.150114)
			(end 0.299974 -0.150114)
			(stroke
				(width 0.1)
				(type default)
			)
			(layer "F.Fab")
		)
		(fp_line
			(start 0.299974 -0.150114)
			(end 0.299974 0.150114)
			(stroke
				(width 0.1)
				(type default)
			)
			(layer "F.Fab")
		)
		(pad "1" smd rect
			(at -0.2667 0 270)
			(size 0.3048 0.381)
			(layers "F.Cu" "F.Mask" "F.Paste")
			(net "P5E_CPU0_PE0_TX_C_DP<3>")
		)
		(pad "2" smd rect
			(at 0.2667 0 270)
			(size 0.3048 0.381)
			(layers "F.Cu" "F.Mask" "F.Paste")
			(net "P5E_CPU0_PE0_TX_DP<3>")
		)
	)
)
